# T6G (Grand Teton) — schematic netlist excerpt (pin names and nets, part order shuffled) for the footprints in the layout excerpt that follows; sources: Cadence DE-HDL packaged netlist, KiCad conversion of 04192023_DAF0TMB3IC0_F0TG_MB_C_brd_V02_OCP.brd

C450  Q_CAP  0.1UF 10V 10% X7S  pkg C0201  page 356 : A = P0V9_CPU1_RT3_2A ; B = GND
C2660  Q_CAP  22UF 4V 20% X6S  pkg C0402  page 75 : A = PVDD18_S5_P1 ; B = GND
R4087  Q_RES  0 5% CHIP  pkg 0402LF  page 150 : A = FW_RECOVERY_R ; B = FW_RECOVERY

(kicad_pcb
	(version 20260206)
	(generator "pcbnew")
	(generator_version "10.0")
	(general
		(thickness 1.6)
		(legacy_teardrops no)
	)
	(paper "A4")
	(title_block
		(title "04192023_DAF0TMB3IC0_F0TG_MB_C_brd_V02_OCP.brd")
		(comment 1 "Grand Teton / footprints 7248-7250 of 8354")
	)
	(layers
		(0 "F.Cu" signal "TOP")
		(4 "In1.Cu" signal "GND")
		(6 "In2.Cu" signal "IN1")
		(8 "In3.Cu" signal "GND1")
		(10 "In4.Cu" signal "IN2")
		(12 "In5.Cu" signal "GND2")
		(14 "In6.Cu" signal "IN3")
		(16 "In7.Cu" signal "GND3")
		(18 "In8.Cu" signal "VCC")
		(20 "In9.Cu" signal "VCC1")
		(22 "In10.Cu" signal "GND4")
		(24 "In11.Cu" signal "IN4")
		(26 "In12.Cu" signal "GND5")
		(28 "In13.Cu" signal "IN5")
		(30 "In14.Cu" signal "GND6")
		(32 "In15.Cu" signal "IN6")
		(34 "In16.Cu" signal "GND7")
		(2 "B.Cu" signal "BOTTOM")
		(9 "F.Adhes" user "F.Adhesive")
		(11 "B.Adhes" user "B.Adhesive")
		(13 "F.Paste" user "Package Geometry/Pastemask Top")
		(15 "B.Paste" user "Package Geometry/Pastemask Bottom")
		(5 "F.SilkS" user "Ref Des/Silkscreen Top")
		(7 "B.SilkS" user "Ref Des/Silkscreen Bottom")
		(1 "F.Mask" user "Board Geometry/Soldermask Top")
		(3 "B.Mask" user "Board Geometry/Soldermask Bottom")
		(17 "Dwgs.User" user "User.Drawings")
		(19 "Cmts.User" user "User.Comments")
		(21 "Eco1.User" user "User.Eco1")
		(23 "Eco2.User" user "User.Eco2")
		(25 "Edge.Cuts" user "Board Geometry/Outline")
		(27 "Margin" user)
		(31 "F.CrtYd" user "Package Geometry/Place Bound Top")
		(29 "B.CrtYd" user "Package Geometry/Place Bound Bottom")
		(35 "F.Fab" user "Ref Des/Assembly Top")
		(33 "B.Fab" user "Ref Des/Assembly Bottom")
	)
	(footprint ""
		(layer "B.Cu")
		(at 117.018562 -388.011162 -90)
		(property "Reference" "C450"
			(at 0 0 90)
			(layer "B.SilkS")
			(hide yes)
			(effects
				(font
					(size 1.27 1.27)
				)
				(justify mirror)
			)
		)
		(property "Value" ""
			(at 0 0 90)
			(layer "B.Fab")
			(effects
				(font
					(size 1.27 1.27)
				)
				(justify mirror)
			)
		)
		(duplicate_pad_numbers_are_jumpers no)
		(fp_line
			(start -0.299974 0.150114)
			(end 0.299974 0.150114)
			(stroke
				(width 0.1)
				(type default)
			)
			(layer "B.Fab")
		)
		(fp_line
			(start 0.299974 0.150114)
			(end 0.299974 -0.150114)
			(stroke
				(width 0.1)
				(type default)
			)
			(layer "B.Fab")
		)
		(fp_line
			(start -0.299974 -0.150114)
			(end -0.299974 0.150114)
			(stroke
				(width 0.1)
				(type default)
			)
			(layer "B.Fab")
		)
		(fp_line
			(start 0.299974 -0.150114)
			(end -0.299974 -0.150114)
			(stroke
				(width 0.1)
				(type default)
			)
			(layer "B.Fab")
		)
		(pad "1" smd rect
			(at 0.2667 0 90)
			(size 0.3048 0.381)
			(layers "B.Cu" "B.Mask" "B.Paste")
			(net "P0V9_CPU1_RT3_2A")
		)
		(pad "2" smd rect
			(at -0.2667 0 90)
			(size 0.3048 0.381)
			(layers "B.Cu" "B.Mask" "B.Paste")
			(net "GND")
		)
	)
	(footprint ""
		(layer "B.Cu")
		(at 105.960164 -256.505456 180)
		(property "Reference" "C2660"
			(at 0 0 0)
			(layer "B.SilkS")
			(hide yes)
			(effects
				(font
					(size 1.27 1.27)
				)
				(justify mirror)
			)
		)
		(property "Value" ""
			(at 0 0 0)
			(layer "B.Fab")
			(effects
				(font
					(size 1.27 1.27)
				)
				(justify mirror)
			)
		)
		(duplicate_pad_numbers_are_jumpers no)
		(fp_line
			(start 0.7874 0.4064)
			(end 0.7874 -0.4064)
			(stroke
				(width 0.1524)
				(type default)
			)
			(layer "B.SilkS")
		)
		(fp_line
			(start 0.7874 -0.4064)
			(end -0.7874 -0.4064)
			(stroke
				(width 0.1524)
				(type default)
			)
			(layer "B.SilkS")
		)
		(fp_line
			(start -0.7874 0.4064)
			(end 0.7874 0.4064)
			(stroke
				(width 0.1524)
				(type default)
			)
			(layer "B.SilkS")
		)
		(fp_line
			(start -0.7874 -0.4064)
			(end -0.7874 0.4064)
			(stroke
				(width 0.1524)
				(type default)
			)
			(layer "B.SilkS")
		)
		(fp_line
			(start 0.67945 0.3048)
			(end 0.67945 -0.305054)
			(stroke
				(width 0.1)
				(type default)
			)
			(layer "B.Fab")
		)
		(fp_line
			(start 0.67945 -0.305054)
			(end 0.12065 -0.305054)
			(stroke
				(width 0.1)
				(type default)
			)
			(layer "B.Fab")
		)
		(fp_line
			(start 0.12065 0.3048)
			(end 0.67945 0.3048)
			(stroke
				(width 0.1)
				(type default)
			)
			(layer "B.Fab")
		)
		(fp_line
			(start 0.12065 0.2794)
			(end 0.12065 0.3048)
			(stroke
				(width 0.1)
				(type default)
			)
			(layer "B.Fab")
		)
		(fp_line
			(start 0.12065 -0.2794)
			(end -0.12065 -0.2794)
			(stroke
				(width 0.1)
				(type default)
			)
			(layer "B.Fab")
		)
		(fp_line
			(start 0.12065 -0.305054)
			(end 0.12065 -0.2794)
			(stroke
				(width 0.1)
				(type default)
			)
			(layer "B.Fab")
		)
		(fp_line
			(start -0.120396 0.3048)
			(end -0.120396 0.2794)
			(stroke
				(width 0.1)
				(type default)
			)
			(layer "B.Fab")
		)
		(fp_line
			(start -0.120396 0.2794)
			(end 0.12065 0.2794)
			(stroke
				(width 0.1)
				(type default)
			)
			(layer "B.Fab")
		)
		(fp_line
			(start -0.12065 -0.2794)
			(end -0.12065 -0.3048)
			(stroke
				(width 0.1)
				(type default)
			)
			(layer "B.Fab")
		)
		(fp_line
			(start -0.12065 -0.3048)
			(end -0.67945 -0.3048)
			(stroke
				(width 0.1)
				(type default)
			)
			(layer "B.Fab")
		)
		(fp_line
			(start -0.67945 0.3048)
			(end -0.120396 0.3048)
			(stroke
				(width 0.1)
				(type default)
			)
			(layer "B.Fab")
		)
		(fp_line
			(start -0.67945 -0.3048)
			(end -0.67945 0.3048)
			(stroke
				(width 0.1)
				(type default)
			)
			(layer "B.Fab")
		)
		(pad "1" smd circle
			(at 0.40005 0)
			(size 0 0)
			(layers "B.Cu" "B.Mask" "B.Paste")
			(net "PVDD18_S5_P1")
		)
		(pad "2" smd circle
			(at -0.40005 0)
			(size 0 0)
			(layers "B.Cu" "B.Mask" "B.Paste")
			(net "GND")
		)
	)
	(footprint ""
		(layer "B.Cu")
		(at 146.3548 -13.772388 90)
		(property "Reference" "R4087"
			(at 0 0 90)
			(layer "B.SilkS")
			(hide yes)
			(effects
				(font
					(size 1.27 1.27)
				)
				(justify mirror)
			)
		)
		(property "Value" ""
			(at 0 0 90)
			(layer "B.Fab")
			(effects
				(font
					(size 1.27 1.27)
				)
				(justify mirror)
			)
		)
		(duplicate_pad_numbers_are_jumpers no)
		(fp_line
			(start 0.7874 -0.4064)
			(end -0.7874 -0.4064)
			(stroke
				(width 0.1524)
				(type default)
			)
			(layer "B.SilkS")
		)
		(fp_line
			(start -0.7874 -0.4064)
			(end -0.7874 0.4064)
			(stroke
				(width 0.1524)
				(type default)
			)
			(layer "B.SilkS")
		)
		(fp_line
			(start 0.7874 0.4064)
			(end 0.7874 -0.4064)
			(stroke
				(width 0.1524)
				(type default)
			)
			(layer "B.SilkS")
		)
		(fp_line
			(start -0.7874 0.4064)
			(end 0.7874 0.4064)
			(stroke
				(width 0.1524)
				(type default)
			)
			(layer "B.SilkS")
		)
		(fp_line
			(start 0.67945 -0.305054)
			(end 0.12065 -0.305054)
			(stroke
				(width 0.1)
				(type default)
			)
			(layer "B.Fab")
		)
		(fp_line
			(start 0.12065 -0.305054)
			(end 0.12065 -0.2794)
			(stroke
				(width 0.1)
				(type default)
			)
			(layer "B.Fab")
		)
		(fp_line
			(start -0.12065 -0.3048)
			(end -0.67945 -0.3048)
			(stroke
				(width 0.1)
				(type default)
			)
			(layer "B.Fab")
		)
		(fp_line
			(start -0.67945 -0.3048)
			(end -0.67945 0.3048)
			(stroke
				(width 0.1)
				(type default)
			)
			(layer "B.Fab")
		)
		(fp_line
			(start 0.12065 -0.2794)
			(end -0.12065 -0.2794)
			(stroke
				(width 0.1)
				(type default)
			)
			(layer "B.Fab")
		)
		(fp_line
			(start -0.12065 -0.2794)
			(end -0.12065 -0.3048)
			(stroke
				(width 0.1)
				(type default)
			)
			(layer "B.Fab")
		)
		(fp_line
			(start 0.12065 0.2794)
			(end 0.12065 0.3048)
			(stroke
				(width 0.1)
				(type default)
			)
			(layer "B.Fab")
		)
		(fp_line
			(start -0.120396 0.2794)
			(end 0.12065 0.2794)
			(stroke
				(width 0.1)
				(type default)
			)
			(layer "B.Fab")
		)
		(fp_line
			(start 0.67945 0.3048)
			(end 0.67945 -0.305054)
			(stroke
				(width 0.1)
				(type default)
			)
			(layer "B.Fab")
		)
		(fp_line
			(start 0.12065 0.3048)
			(end 0.67945 0.3048)
			(stroke
				(width 0.1)
				(type default)
			)
			(layer "B.Fab")
		)
		(fp_line
			(start -0.120396 0.3048)
			(end -0.120396 0.2794)
			(stroke
				(width 0.1)
				(type default)
			)
			(layer "B.Fab")
		)
		(fp_line
			(start -0.67945 0.3048)
			(end -0.120396 0.3048)
			(stroke
				(width 0.1)
				(type default)
			)
			(layer "B.Fab")
		)
		(pad "1" smd circle
			(at 0.40005 0 270)
			(size 0 0)
			(layers "B.Cu" "B.Mask" "B.Paste")
			(net "FW_RECOVERY_R")
		)
		(pad "2" smd circle
			(at -0.40005 0 270)
			(size 0 0)
			(layers "B.Cu" "B.Mask" "B.Paste")
			(net "FW_RECOVERY")
		)
	)
)
